(kicad_pcb
	(version 20260206)
	(generator "pcbnew")
	(generator_version "10.0")
	(general
		(thickness 1.6)
		(legacy_teardrops no)
	)
	(paper "A4")
	(title_block
		(title "baseboard — 13948-1b.1110WZS1818.brd")
		(comment 1 "Honey Badger (Wiwynn) / footprints 1026-1027 of 2523")
	)
	(layers
		(0 "F.Cu" signal "TOP")
		(4 "In1.Cu" signal "L2GND")
		(6 "In2.Cu" signal "L3")
		(8 "In3.Cu" signal "L4VCC")
		(10 "In4.Cu" signal "L5VCC")
		(12 "In5.Cu" signal "L6")
		(14 "In6.Cu" signal "L7GND")
		(2 "B.Cu" signal "BOTTOM")
		(9 "F.Adhes" user "F.Adhesive")
		(11 "B.Adhes" user "B.Adhesive")
		(13 "F.Paste" user "Package Geometry/Pastemask Top")
		(15 "B.Paste" user "Package Geometry/Pastemask Bottom")
		(5 "F.SilkS" user "Ref Des/Silkscreen Top")
		(7 "B.SilkS" user "Ref Des/Silkscreen Bottom")
		(1 "F.Mask" user "Board Geometry/Soldermask Top")
		(3 "B.Mask" user "Board Geometry/Soldermask Bottom")
		(17 "Dwgs.User" user "User.Drawings")
		(19 "Cmts.User" user "User.Comments")
		(21 "Eco1.User" user "User.Eco1")
		(23 "Eco2.User" user "User.Eco2")
		(25 "Edge.Cuts" user "Board Geometry/Outline")
		(27 "Margin" user)
		(31 "F.CrtYd" user "Package Geometry/Place Bound Top")
		(29 "B.CrtYd" user "Package Geometry/Place Bound Bottom")
		(35 "F.Fab" user "Ref Des/Assembly Top")
		(33 "B.Fab" user "Ref Des/Assembly Bottom")
	)
	(footprint ""
		(layer "F.Cu")
		(at 204.089 -218.567 90)
		(property "Reference" "C82"
			(at 0 0 90)
			(layer "F.SilkS")
			(hide yes)
			(effects
				(font
					(size 1.27 1.27)
				)
			)
		)
		(property "Value" "SCD1U16V2KX-3GP"
			(at 1.1811 -2.7051 90)
			(unlocked yes)
			(layer "F.Fab")
			(hide yes)
			(effects
				(font
					(size 1.016 1.016)
					(thickness 0.1524)
				)
			)
		)
		(property "Device Type" "C402H22"
			(at 1.1811 -4.2291 90)
			(unlocked yes)
			(layer "F.Fab")
			(hide yes)
			(effects
				(font
					(size 1.016 1.016)
					(thickness 0.1524)
				)
			)
		)
		(duplicate_pad_numbers_are_jumpers no)
		(fp_rect
			(start -0.4318 0.9525)
			(end 0.4318 -0.9525)
			(stroke
				(width 0)
				(type default)
			)
			(fill no)
			(layer "F.CrtYd")
		)
		(fp_rect
			(start -0.4318 0.9525)
			(end 0.4318 -0.9525)
			(stroke
				(width 0)
				(type default)
			)
			(fill no)
			(layer "F.Fab")
		)
		(pad "1" smd custom
			(at 0 -0.4445 90)
			(size 0.1524 0.1524)
			(layers "F.Cu" "F.Mask" "F.Paste")
			(net "P3V3_STBY")
			(options
				(clearance outline)
				(anchor circle)
			)
			(primitives
				(gr_poly
					(pts
						(arc
							(start 0.3048 -0.2032)
							(mid 0.275042 -0.275042)
							(end 0.2032 -0.3048)
						)
						(arc
							(start -0.2032 -0.3048)
							(mid -0.275042 -0.275042)
							(end -0.3048 -0.2032)
						)
						(arc
							(start -0.3048 0.2032)
							(mid -0.275042 0.275042)
							(end -0.2032 0.3048)
						)
						(arc
							(start 0.2032 0.3048)
							(mid 0.275042 0.275042)
							(end 0.3048 0.2032)
						)
					)
					(width 0)
					(fill yes)
				)
			)
		)
		(pad "2" smd custom
			(at 0 0.4445 90)
			(size 0.1524 0.1524)
			(layers "F.Cu" "F.Mask" "F.Paste")
			(net "GND")
			(options
				(clearance outline)
				(anchor circle)
			)
			(primitives
				(gr_poly
					(pts
						(arc
							(start 0.3048 -0.2032)
							(mid 0.275042 -0.275042)
							(end 0.2032 -0.3048)
						)
						(arc
							(start -0.2032 -0.3048)
							(mid -0.275042 -0.275042)
							(end -0.3048 -0.2032)
						)
						(arc
							(start -0.3048 0.2032)
							(mid -0.275042 0.275042)
							(end -0.2032 0.3048)
						)
						(arc
							(start 0.2032 0.3048)
							(mid 0.275042 0.275042)
							(end 0.3048 0.2032)
						)
					)
					(width 0)
					(fill yes)
				)
			)
		)
	)
	(footprint ""
		(layer "F.Cu")
		(at 170.561 -133.096 -90)
		(property "Reference" "PL8"
			(at 0 0 270)
			(layer "F.SilkS")
			(hide yes)
			(effects
				(font
					(size 1.27 1.27)
				)
			)
		)
		(property "Value" "BLM41PG600-GP"
			(at -3.690874 -7.441184 270)
			(unlocked yes)
			(layer "F.Fab")
			(hide yes)
			(effects
				(font
					(size 1.016 1.016)
					(thickness 0.1524)
				)
			)
		)
		(property "Device Type" "L451616H71"
			(at -3.690874 -5.917184 270)
			(unlocked yes)
			(layer "F.Fab")
			(hide yes)
			(effects
				(font
					(size 1.016 1.016)
					(thickness 0.1524)
				)
			)
		)
		(duplicate_pad_numbers_are_jumpers no)
		(fp_line
			(start -2.8702 1.2954)
			(end 2.8702 1.2954)
			(stroke
				(width 0.1524)
				(type default)
			)
			(layer "F.SilkS")
		)
		(fp_line
			(start -2.8702 1.2954)
			(end 2.8702 1.2954)
			(stroke
				(width 0.1524)
				(type default)
			)
			(layer "F.SilkS")
		)
		(fp_line
			(start 2.8702 1.2954)
			(end 2.8702 -1.2954)
			(stroke
				(width 0.1524)
				(type default)
			)
			(layer "F.SilkS")
		)
		(fp_line
			(start 2.8702 1.2954)
			(end 2.8702 -1.2954)
			(stroke
				(width 0.1524)
				(type default)
			)
			(layer "F.SilkS")
		)
		(fp_line
			(start -2.8702 -1.2954)
			(end -2.8702 1.2954)
			(stroke
				(width 0.1524)
				(type default)
			)
			(layer "F.SilkS")
		)
		(fp_line
			(start -2.8702 -1.2954)
			(end -2.8702 1.2954)
			(stroke
				(width 0.1524)
				(type default)
			)
			(layer "F.SilkS")
		)
		(fp_line
			(start 2.8702 -1.2954)
			(end -2.8702 -1.2954)
			(stroke
				(width 0.1524)
				(type default)
			)
			(layer "F.SilkS")
		)
		(fp_line
			(start 2.8702 -1.2954)
			(end -2.8702 -1.2954)
			(stroke
				(width 0.1524)
				(type default)
			)
			(layer "F.SilkS")
		)
		(fp_poly
			(pts
				(xy -2.8702 1.2954) (xy 2.8702 1.2954) (xy 2.8702 -1.2954) (xy -2.8702 -1.2954)
			)
			(stroke
				(width 0)
				(type default)
			)
			(fill no)
			(layer "F.CrtYd")
		)
		(fp_poly
			(pts
				(xy -2.8702 1.2954) (xy 2.8702 1.2954) (xy 2.8702 -1.2954) (xy -2.8702 -1.2954)
			)
			(stroke
				(width 0)
				(type default)
			)
			(fill no)
			(layer "F.Fab")
		)
		(pad "1" smd rect
			(at -1.9685 0 270)
			(size 1.3716 1.8796)
			(layers "F.Cu" "F.Mask" "F.Paste")
			(net "P12V")
		)
		(pad "2" smd rect
			(at 1.9685 0 270)
			(size 1.3716 1.8796)
			(layers "F.Cu" "F.Mask" "F.Paste")
			(net "P0V9_E_VIN")
		)
	)
)
